(kicad_pcb
	(version 20260206)
	(generator "pcbnew")
	(generator_version "10.0")
	(general
		(thickness 1.6)
		(legacy_teardrops no)
	)
	(paper "A4")
	(title_block
		(title "Bryce Canyon_R.DPB_16317-1_OCP.brd")
		(comment 1 "Bryce Canyon / footprints 1803-1809 of 2099")
	)
	(layers
		(0 "F.Cu" signal "TOP")
		(4 "In1.Cu" signal "L2GND")
		(6 "In2.Cu" signal "L3")
		(8 "In3.Cu" signal "L4VCC")
		(10 "In4.Cu" signal "L5VCC")
		(12 "In5.Cu" signal "L6")
		(14 "In6.Cu" signal "L7GND")
		(2 "B.Cu" signal "BOTTOM")
		(9 "F.Adhes" user "F.Adhesive")
		(11 "B.Adhes" user "B.Adhesive")
		(13 "F.Paste" user "Package Geometry/Pastemask Top")
		(15 "B.Paste" user "Package Geometry/Pastemask Bottom")
		(5 "F.SilkS" user "Ref Des/Silkscreen Top")
		(7 "B.SilkS" user "Ref Des/Silkscreen Bottom")
		(1 "F.Mask" user "Board Geometry/Soldermask Top")
		(3 "B.Mask" user "Board Geometry/Soldermask Bottom")
		(17 "Dwgs.User" user "User.Drawings")
		(19 "Cmts.User" user "User.Comments")
		(21 "Eco1.User" user "User.Eco1")
		(23 "Eco2.User" user "User.Eco2")
		(25 "Edge.Cuts" user "Board Geometry/Outline")
		(27 "Margin" user)
		(31 "F.CrtYd" user "Package Geometry/Place Bound Top")
		(29 "B.CrtYd" user "Package Geometry/Place Bound Bottom")
		(35 "F.Fab" user "Ref Des/Assembly Top")
		(33 "B.Fab" user "Ref Des/Assembly Bottom")
	)
	(footprint ""
		(layer "F.Cu")
		(at 243.0907 -356.4636 -90)
		(property "Reference" "R1038"
			(at 0 0 270)
			(layer "F.SilkS")
			(hide yes)
			(effects
				(font
					(size 1.27 1.27)
				)
			)
		)
		(property "Value" "10R2F-L-GP"
			(at 0.064008 -3.993896 270)
			(unlocked yes)
			(layer "F.Fab")
			(hide yes)
			(effects
				(font
					(size 1.016 1.016)
					(thickness 0.1524)
				)
			)
		)
		(property "Device Type" "R402H14"
			(at 0.064008 -5.517896 270)
			(unlocked yes)
			(layer "F.Fab")
			(hide yes)
			(effects
				(font
					(size 1.016 1.016)
					(thickness 0.1524)
				)
			)
		)
		(duplicate_pad_numbers_are_jumpers no)
		(fp_line
			(start -0.508 -0.9398)
			(end -0.508 0.9398)
			(stroke
				(width 0.1524)
				(type default)
			)
			(layer "F.SilkS")
		)
		(fp_line
			(start 0.508 -0.9398)
			(end -0.508 -0.9398)
			(stroke
				(width 0.1524)
				(type default)
			)
			(layer "F.SilkS")
		)
		(fp_rect
			(start -0.508 0.9398)
			(end 0.508 -0.9398)
			(stroke
				(width 0)
				(type default)
			)
			(fill no)
			(layer "F.CrtYd")
		)
		(fp_rect
			(start -0.508 0.9398)
			(end 0.508 -0.9398)
			(stroke
				(width 0)
				(type default)
			)
			(fill no)
			(layer "F.Fab")
		)
		(pad "1" smd custom
			(at 0 -0.4445 270)
			(size 0.1397 0.1397)
			(layers "F.Cu" "F.Mask" "F.Paste")
			(net "MB3_CM_SENSE_R1_N")
			(options
				(clearance outline)
				(anchor circle)
			)
			(primitives
				(gr_poly
					(pts
						(arc
							(start -0.1778 -0.2794)
							(mid -0.249642 -0.249642)
							(end -0.2794 -0.1778)
						)
						(arc
							(start -0.2794 0.1778)
							(mid -0.249642 0.249642)
							(end -0.1778 0.2794)
						)
						(arc
							(start 0.1778 0.2794)
							(mid 0.249642 0.249642)
							(end 0.2794 0.1778)
						)
						(arc
							(start 0.2794 -0.1778)
							(mid 0.249642 -0.249642)
							(end 0.1778 -0.2794)
						)
					)
					(width 0)
					(fill yes)
				)
			)
		)
		(pad "2" smd custom
			(at 0 0.4445 270)
			(size 0.1397 0.1397)
			(layers "F.Cu" "F.Mask" "F.Paste")
			(net "MB3_CM_SENSE_N")
			(options
				(clearance outline)
				(anchor circle)
			)
			(primitives
				(gr_poly
					(pts
						(arc
							(start -0.1778 -0.2794)
							(mid -0.249642 -0.249642)
							(end -0.2794 -0.1778)
						)
						(arc
							(start -0.2794 0.1778)
							(mid -0.249642 0.249642)
							(end -0.1778 0.2794)
						)
						(arc
							(start 0.1778 0.2794)
							(mid 0.249642 0.249642)
							(end 0.2794 0.1778)
						)
						(arc
							(start 0.2794 -0.1778)
							(mid 0.249642 -0.249642)
							(end 0.1778 -0.2794)
						)
					)
					(width 0)
					(fill yes)
				)
			)
		)
	)
	(footprint ""
		(layer "F.Cu")
		(at 113.03 -246.634)
		(property "Reference" "R219"
			(at 0 0 0)
			(layer "F.SilkS")
			(hide yes)
			(effects
				(font
					(size 1.27 1.27)
				)
			)
		)
		(property "Value" "0R2J-2-GP"
			(at 0.064008 -3.993896 0)
			(unlocked yes)
			(layer "F.Fab")
			(hide yes)
			(effects
				(font
					(size 1.016 1.016)
					(thickness 0.1524)
				)
			)
		)
		(property "Device Type" "R402H16"
			(at 0.064008 -5.517896 0)
			(unlocked yes)
			(layer "F.Fab")
			(hide yes)
			(effects
				(font
					(size 1.016 1.016)
					(thickness 0.1524)
				)
			)
		)
		(duplicate_pad_numbers_are_jumpers no)
		(fp_line
			(start -0.508 -0.9398)
			(end -0.508 0.9398)
			(stroke
				(width 0.1524)
				(type default)
			)
			(layer "F.SilkS")
		)
		(fp_line
			(start 0.508 -0.9398)
			(end -0.508 -0.9398)
			(stroke
				(width 0.1524)
				(type default)
			)
			(layer "F.SilkS")
		)
		(fp_rect
			(start -0.508 0.9398)
			(end 0.508 -0.9398)
			(stroke
				(width 0)
				(type default)
			)
			(fill no)
			(layer "F.CrtYd")
		)
		(fp_rect
			(start -0.508 0.9398)
			(end 0.508 -0.9398)
			(stroke
				(width 0)
				(type default)
			)
			(fill no)
			(layer "F.Fab")
		)
		(pad "1" smd custom
			(at 0 -0.4445)
			(size 0.1397 0.1397)
			(layers "F.Cu" "F.Mask" "F.Paste")
			(net "SW_HDD_G3")
			(options
				(clearance outline)
				(anchor circle)
			)
			(primitives
				(gr_poly
					(pts
						(arc
							(start -0.1778 -0.2794)
							(mid -0.249642 -0.249642)
							(end -0.2794 -0.1778)
						)
						(arc
							(start -0.2794 0.1778)
							(mid -0.249642 0.249642)
							(end -0.1778 0.2794)
						)
						(arc
							(start 0.1778 0.2794)
							(mid 0.249642 0.249642)
							(end 0.2794 0.1778)
						)
						(arc
							(start 0.2794 -0.1778)
							(mid 0.249642 -0.249642)
							(end 0.1778 -0.2794)
						)
					)
					(width 0)
					(fill yes)
				)
			)
		)
		(pad "2" smd custom
			(at 0 0.4445)
			(size 0.1397 0.1397)
			(layers "F.Cu" "F.Mask" "F.Paste")
			(net "SW_HDD_R3")
			(options
				(clearance outline)
				(anchor circle)
			)
			(primitives
				(gr_poly
					(pts
						(arc
							(start -0.1778 -0.2794)
							(mid -0.249642 -0.249642)
							(end -0.2794 -0.1778)
						)
						(arc
							(start -0.2794 0.1778)
							(mid -0.249642 0.249642)
							(end -0.1778 0.2794)
						)
						(arc
							(start 0.1778 0.2794)
							(mid 0.249642 0.249642)
							(end 0.2794 0.1778)
						)
						(arc
							(start 0.2794 -0.1778)
							(mid 0.249642 -0.249642)
							(end 0.1778 -0.2794)
						)
					)
					(width 0)
					(fill yes)
				)
			)
		)
	)
	(footprint ""
		(layer "F.Cu")
		(at 189.799976 -93.999812)
		(property "Reference" ""
			(at 0 0 0)
			(layer "F.SilkS")
			(hide yes)
			(effects
				(font
					(size 1.27 1.27)
				)
			)
		)
		(property "Value" "*"
			(at -8.398764 -8.057642 0)
			(unlocked yes)
			(layer "F.Fab")
			(hide yes)
			(effects
				(font
					(size 1.016 1.016)
					(thickness 0.1524)
				)
			)
		)
		(duplicate_pad_numbers_are_jumpers no)
		(fp_poly
			(pts
				(arc
					(start 7.3152 0)
					(mid 0 7.3152)
					(end -7.3152 0)
				)
				(arc
					(start -7.3152 -5.9944)
					(mid 0 -13.3096)
					(end 7.3152 -5.9944)
				)
			)
			(stroke
				(width 0)
				(type default)
			)
			(fill no)
			(layer "B.CrtYd")
		)
		(fp_poly
			(pts
				(arc
					(start 7.3152 0)
					(mid 0 7.3152)
					(end -7.3152 0)
				)
				(arc
					(start -7.3152 -5.9944)
					(mid 0 -13.3096)
					(end 7.3152 -5.9944)
				)
			)
			(stroke
				(width 0)
				(type default)
			)
			(fill no)
			(layer "F.CrtYd")
		)
		(fp_poly
			(pts
				(arc
					(start 7.3152 0)
					(mid 0 7.3152)
					(end -7.3152 0)
				)
				(arc
					(start -7.3152 -5.9944)
					(mid 0 -13.3096)
					(end 7.3152 -5.9944)
				)
			)
			(stroke
				(width 0)
				(type default)
			)
			(fill no)
			(layer "B.Fab")
		)
		(fp_poly
			(pts
				(arc
					(start 7.3152 0)
					(mid 0 7.3152)
					(end -7.3152 0)
				)
				(arc
					(start -7.3152 -5.9944)
					(mid 0 -13.3096)
					(end 7.3152 -5.9944)
				)
			)
			(stroke
				(width 0)
				(type default)
			)
			(fill no)
			(layer "F.Fab")
		)
		(pad "1" thru_hole oval
			(at 0 0)
			(size 14.0208 20.0152)
			(drill 0.0254
				(offset 0 -2.9972)
			)
			(layers "*.Cu" "*.Mask")
			(remove_unused_layers no)
			(net "Net_19")
			(clearance -1.002284)
			(thermal_gap 0.1524)
			(padstack
				(mode front_inner_back)
				(layer "Inner"
					(shape custom)
					(size 2.928012 2.928012)
					(options
						(anchor circle)
					)
					(primitives
						(gr_poly
							(pts
								(arc
									(start 4.571746 -2.084324)
									(mid 0.000333 7.430372)
									(end -4.571492 -2.084324)
								)
								(arc
									(start -4.571492 -2.084324)
									(mid -3.570296 -3.611977)
									(end -2.875026 -5.30098)
								)
								(arc
									(start -2.875026 -5.30098)
									(mid 0.000217 -7.43089)
									(end 2.87528 -5.30098)
								)
								(arc
									(start 2.87528 -5.30098)
									(mid 3.570511 -3.611956)
									(end 4.571746 -2.084324)
								)
							)
							(width 0)
							(fill yes)
						)
					)
					(clearance 0.1524)
				)
				(layer "B.Cu"
					(shape oval)
					(size 14.0208 20.0152)
					(offset 0 -2.9972)
					(clearance -1.002284)
				)
			)
		)
		(zone
			(layers "F.Cu" "B.Cu" "In1.Cu" "In2.Cu" "In3.Cu" "In4.Cu" "In5.Cu" "In6.Cu")
			(hatch none 0.5)
			(connect_pads
				(clearance 0)
			)
			(min_thickness 0.25)
			(keepout
				(tracks not_allowed)
				(vias allowed)
				(pads allowed)
				(copperpour not_allowed)
				(footprints allowed)
			)
			(placement
				(enabled no)
				(sheetname "")
			)
			(fill
				(thermal_gap 0.5)
				(thermal_bridge_width 0.5)
				(island_removal_mode 0)
			)
			(polygon
				(pts
					(arc
						(start 182.789576 -99.994212)
						(mid 189.799976 -107.004612)
						(end 196.810376 -99.994212)
					)
					(arc
						(start 196.810376 -93.999812)
						(mid 189.799976 -86.989412)
						(end 182.789576 -93.999812)
					)
				)
			)
		)
	)
	(footprint ""
		(layer "F.Cu")
		(at 368.427 -131.826 180)
		(property "Reference" "R521"
			(at 0 0 180)
			(layer "F.SilkS")
			(hide yes)
			(effects
				(font
					(size 1.27 1.27)
				)
			)
		)
		(property "Value" "4K7R2J-2-GP"
			(at 0.064008 -3.993896 180)
			(unlocked yes)
			(layer "F.Fab")
			(hide yes)
			(effects
				(font
					(size 1.016 1.016)
					(thickness 0.1524)
				)
			)
		)
		(property "Device Type" "R402H16"
			(at 0.064008 -5.517896 180)
			(unlocked yes)
			(layer "F.Fab")
			(hide yes)
			(effects
				(font
					(size 1.016 1.016)
					(thickness 0.1524)
				)
			)
		)
		(duplicate_pad_numbers_are_jumpers no)
		(fp_line
			(start 0.508 -0.9398)
			(end -0.508 -0.9398)
			(stroke
				(width 0.1524)
				(type default)
			)
			(layer "F.SilkS")
		)
		(fp_line
			(start -0.508 -0.9398)
			(end -0.508 0.9398)
			(stroke
				(width 0.1524)
				(type default)
			)
			(layer "F.SilkS")
		)
		(fp_rect
			(start -0.508 0.9398)
			(end 0.508 -0.9398)
			(stroke
				(width 0)
				(type default)
			)
			(fill no)
			(layer "F.CrtYd")
		)
		(fp_rect
			(start -0.508 0.9398)
			(end 0.508 -0.9398)
			(stroke
				(width 0)
				(type default)
			)
			(fill no)
			(layer "F.Fab")
		)
		(pad "1" smd custom
			(at 0 -0.4445 180)
			(size 0.1397 0.1397)
			(layers "F.Cu" "F.Mask" "F.Paste")
			(net "P12V_B")
			(options
				(clearance outline)
				(anchor circle)
			)
			(primitives
				(gr_poly
					(pts
						(arc
							(start -0.1778 -0.2794)
							(mid -0.249642 -0.249642)
							(end -0.2794 -0.1778)
						)
						(arc
							(start -0.2794 0.1778)
							(mid -0.249642 0.249642)
							(end -0.1778 0.2794)
						)
						(arc
							(start 0.1778 0.2794)
							(mid 0.249642 0.249642)
							(end 0.2794 0.1778)
						)
						(arc
							(start 0.2794 -0.1778)
							(mid 0.249642 -0.249642)
							(end 0.1778 -0.2794)
						)
					)
					(width 0)
					(fill yes)
				)
			)
		)
		(pad "2" smd custom
			(at 0 0.4445 180)
			(size 0.1397 0.1397)
			(layers "F.Cu" "F.Mask" "F.Paste")
			(net "SW_HDD_R19")
			(options
				(clearance outline)
				(anchor circle)
			)
			(primitives
				(gr_poly
					(pts
						(arc
							(start -0.1778 -0.2794)
							(mid -0.249642 -0.249642)
							(end -0.2794 -0.1778)
						)
						(arc
							(start -0.2794 0.1778)
							(mid -0.249642 0.249642)
							(end -0.1778 0.2794)
						)
						(arc
							(start 0.1778 0.2794)
							(mid 0.249642 0.249642)
							(end 0.2794 0.1778)
						)
						(arc
							(start 0.2794 -0.1778)
							(mid 0.249642 -0.249642)
							(end 0.1778 -0.2794)
						)
					)
					(width 0)
					(fill yes)
				)
			)
		)
	)
	(footprint ""
		(layer "F.Cu")
		(at 248.285 -304.038 90)
		(property "Reference" "R1089"
			(at 0 0 90)
			(layer "F.SilkS")
			(hide yes)
			(effects
				(font
					(size 1.27 1.27)
				)
			)
		)
		(property "Value" "0R2J-2-GP"
			(at 0.064008 -3.993896 90)
			(unlocked yes)
			(layer "F.Fab")
			(hide yes)
			(effects
				(font
					(size 1.016 1.016)
					(thickness 0.1524)
				)
			)
		)
		(property "Device Type" "R402H16"
			(at 0.064008 -5.517896 90)
			(unlocked yes)
			(layer "F.Fab")
			(hide yes)
			(effects
				(font
					(size 1.016 1.016)
					(thickness 0.1524)
				)
			)
		)
		(duplicate_pad_numbers_are_jumpers no)
		(fp_line
			(start 0.508 -0.9398)
			(end -0.508 -0.9398)
			(stroke
				(width 0.1524)
				(type default)
			)
			(layer "F.SilkS")
		)
		(fp_line
			(start -0.508 -0.9398)
			(end -0.508 0.9398)
			(stroke
				(width 0.1524)
				(type default)
			)
			(layer "F.SilkS")
		)
		(fp_rect
			(start -0.508 0.9398)
			(end 0.508 -0.9398)
			(stroke
				(width 0)
				(type default)
			)
			(fill no)
			(layer "F.CrtYd")
		)
		(fp_rect
			(start -0.508 0.9398)
			(end 0.508 -0.9398)
			(stroke
				(width 0)
				(type default)
			)
			(fill no)
			(layer "F.Fab")
		)
		(pad "1" smd custom
			(at 0 -0.4445 90)
			(size 0.1397 0.1397)
			(layers "F.Cu" "F.Mask" "F.Paste")
			(net "MAX31790_A_SDA")
			(options
				(clearance outline)
				(anchor circle)
			)
			(primitives
				(gr_poly
					(pts
						(arc
							(start -0.1778 -0.2794)
							(mid -0.249642 -0.249642)
							(end -0.2794 -0.1778)
						)
						(arc
							(start -0.2794 0.1778)
							(mid -0.249642 0.249642)
							(end -0.1778 0.2794)
						)
						(arc
							(start 0.1778 0.2794)
							(mid 0.249642 0.249642)
							(end 0.2794 0.1778)
						)
						(arc
							(start 0.2794 -0.1778)
							(mid 0.249642 -0.249642)
							(end 0.1778 -0.2794)
						)
					)
					(width 0)
					(fill yes)
				)
			)
		)
		(pad "2" smd custom
			(at 0 0.4445 90)
			(size 0.1397 0.1397)
			(layers "F.Cu" "F.Mask" "F.Paste")
			(net "I2C_DPB_A_SDA_BUF")
			(options
				(clearance outline)
				(anchor circle)
			)
			(primitives
				(gr_poly
					(pts
						(arc
							(start -0.1778 -0.2794)
							(mid -0.249642 -0.249642)
							(end -0.2794 -0.1778)
						)
						(arc
							(start -0.2794 0.1778)
							(mid -0.249642 0.249642)
							(end -0.1778 0.2794)
						)
						(arc
							(start 0.1778 0.2794)
							(mid 0.249642 0.249642)
							(end 0.2794 0.1778)
						)
						(arc
							(start 0.2794 -0.1778)
							(mid 0.249642 -0.249642)
							(end 0.1778 -0.2794)
						)
					)
					(width 0)
					(fill yes)
				)
			)
		)
	)
	(footprint ""
		(layer "F.Cu")
		(at 260.73481 -224.785174)
		(property "Reference" "C53"
			(at 0 0 0)
			(layer "F.SilkS")
			(hide yes)
			(effects
				(font
					(size 1.27 1.27)
				)
			)
		)
		(property "Value" "SCD1U16V2KX-3GP"
			(at 1.1811 -2.7051 0)
			(unlocked yes)
			(layer "F.Fab")
			(hide yes)
			(effects
				(font
					(size 1.016 1.016)
					(thickness 0.1524)
				)
			)
		)
		(property "Device Type" "C402H22"
			(at 1.1811 -4.2291 0)
			(unlocked yes)
			(layer "F.Fab")
			(hide yes)
			(effects
				(font
					(size 1.016 1.016)
					(thickness 0.1524)
				)
			)
		)
		(duplicate_pad_numbers_are_jumpers no)
		(fp_rect
			(start -0.4318 0.9525)
			(end 0.4318 -0.9525)
			(stroke
				(width 0)
				(type default)
			)
			(fill no)
			(layer "F.CrtYd")
		)
		(fp_rect
			(start -0.4318 0.9525)
			(end 0.4318 -0.9525)
			(stroke
				(width 0)
				(type default)
			)
			(fill no)
			(layer "F.Fab")
		)
		(pad "1" smd custom
			(at 0 -0.4445)
			(size 0.1524 0.1524)
			(layers "F.Cu" "F.Mask" "F.Paste")
			(net "P5V_B_4_SENSE")
			(options
				(clearance outline)
				(anchor circle)
			)
			(primitives
				(gr_poly
					(pts
						(arc
							(start 0.3048 -0.2032)
							(mid 0.275042 -0.275042)
							(end 0.2032 -0.3048)
						)
						(arc
							(start -0.2032 -0.3048)
							(mid -0.275042 -0.275042)
							(end -0.3048 -0.2032)
						)
						(arc
							(start -0.3048 0.2032)
							(mid -0.275042 0.275042)
							(end -0.2032 0.3048)
						)
						(arc
							(start 0.2032 0.3048)
							(mid 0.275042 0.275042)
							(end 0.3048 0.2032)
						)
					)
					(width 0)
					(fill yes)
				)
			)
		)
		(pad "2" smd custom
			(at 0 0.4445)
			(size 0.1524 0.1524)
			(layers "F.Cu" "F.Mask" "F.Paste")
			(net "GND")
			(options
				(clearance outline)
				(anchor circle)
			)
			(primitives
				(gr_poly
					(pts
						(arc
							(start 0.3048 -0.2032)
							(mid 0.275042 -0.275042)
							(end 0.2032 -0.3048)
						)
						(arc
							(start -0.2032 -0.3048)
							(mid -0.275042 -0.275042)
							(end -0.3048 -0.2032)
						)
						(arc
							(start -0.3048 0.2032)
							(mid -0.275042 0.275042)
							(end -0.2032 0.3048)
						)
						(arc
							(start 0.2032 0.3048)
							(mid 0.275042 0.275042)
							(end 0.3048 0.2032)
						)
					)
					(width 0)
					(fill yes)
				)
			)
		)
	)
	(footprint ""
		(layer "F.Cu")
		(at 111.379 -254.127 -90)
		(property "Reference" "C77"
			(at 0 0 270)
			(layer "F.SilkS")
			(hide yes)
			(effects
				(font
					(size 1.27 1.27)
				)
			)
		)
		(property "Value" "SCD033U25V2KX-GP"
			(at 1.1811 -2.7051 270)
			(unlocked yes)
			(layer "F.Fab")
			(hide yes)
			(effects
				(font
					(size 1.016 1.016)
					(thickness 0.1524)
				)
			)
		)
		(property "Device Type" "C402H22"
			(at 1.1811 -4.2291 270)
			(unlocked yes)
			(layer "F.Fab")
			(hide yes)
			(effects
				(font
					(size 1.016 1.016)
					(thickness 0.1524)
				)
			)
		)
		(duplicate_pad_numbers_are_jumpers no)
		(fp_rect
			(start -0.4318 0.9525)
			(end 0.4318 -0.9525)
			(stroke
				(width 0)
				(type default)
			)
			(fill no)
			(layer "F.CrtYd")
		)
		(fp_rect
			(start -0.4318 0.9525)
			(end 0.4318 -0.9525)
			(stroke
				(width 0)
				(type default)
			)
			(fill no)
			(layer "F.Fab")
		)
		(pad "1" smd custom
			(at 0 -0.4445 270)
			(size 0.1524 0.1524)
			(layers "F.Cu" "F.Mask" "F.Paste")
			(net "SW_HDD_P3")
			(options
				(clearance outline)
				(anchor circle)
			)
			(primitives
				(gr_poly
					(pts
						(arc
							(start 0.3048 -0.2032)
							(mid 0.275042 -0.275042)
							(end 0.2032 -0.3048)
						)
						(arc
							(start -0.2032 -0.3048)
							(mid -0.275042 -0.275042)
							(end -0.3048 -0.2032)
						)
						(arc
							(start -0.3048 0.2032)
							(mid -0.275042 0.275042)
							(end -0.2032 0.3048)
						)
						(arc
							(start 0.2032 0.3048)
							(mid 0.275042 0.275042)
							(end 0.3048 0.2032)
						)
					)
					(width 0)
					(fill yes)
				)
			)
		)
		(pad "2" smd custom
			(at 0 0.4445 270)
			(size 0.1524 0.1524)
			(layers "F.Cu" "F.Mask" "F.Paste")
			(net "GND")
			(options
				(clearance outline)
				(anchor circle)
			)
			(primitives
				(gr_poly
					(pts
						(arc
							(start 0.3048 -0.2032)
							(mid 0.275042 -0.275042)
							(end 0.2032 -0.3048)
						)
						(arc
							(start -0.2032 -0.3048)
							(mid -0.275042 -0.275042)
							(end -0.3048 -0.2032)
						)
						(arc
							(start -0.3048 0.2032)
							(mid -0.275042 0.275042)
							(end -0.2032 0.3048)
						)
						(arc
							(start 0.2032 0.3048)
							(mid 0.275042 0.275042)
							(end 0.3048 0.2032)
						)
					)
					(width 0)
					(fill yes)
				)
			)
		)
	)
)
